(kicad_pcb
	(version 20241229)
	(generator "pcbnew")
	(generator_version "9.0")
	(general
		(thickness 1.62)
		(legacy_teardrops no)
	)
	(paper "A4")
	(title_block
		(title "OCuLink to 10GbE adapter")
		(date "2026-02-23")
		(rev "1.1.0")
		(company "Antmicro Ltd")
		(comment 1 "www.antmicro.com")
		(comment 9 "footprints 473-478 of 510")
	)
	(layers
		(0 "F.Cu" signal)
		(4 "In1.Cu" signal)
		(6 "In2.Cu" signal)
		(8 "In3.Cu" signal)
		(10 "In4.Cu" signal)
		(12 "In5.Cu" signal)
		(14 "In6.Cu" signal)
		(2 "B.Cu" signal)
		(9 "F.Adhes" user "F.Adhesive")
		(11 "B.Adhes" user "B.Adhesive")
		(13 "F.Paste" user)
		(15 "B.Paste" user)
		(5 "F.SilkS" user "F.Silkscreen")
		(7 "B.SilkS" user "B.Silkscreen")
		(1 "F.Mask" user)
		(3 "B.Mask" user)
		(17 "Dwgs.User" user "User.Drawings")
		(19 "Cmts.User" user "User.Comments")
		(21 "Eco1.User" user "User.Eco1")
		(23 "Eco2.User" user "User.Eco2")
		(25 "Edge.Cuts" user)
		(27 "Margin" user)
		(31 "F.CrtYd" user "F.Courtyard")
		(29 "B.CrtYd" user "B.Courtyard")
		(35 "F.Fab" user)
		(33 "B.Fab" user)
	)
	(footprint "antmicro-footprints:C_0402_1005Metric"
		(layer "B.Cu")
		(at 81.32 105.08 90)
		(descr "Capacitor SMD 0402")
		(tags "capacitor SMD 0402")
		(property "Reference" "C85"
			(at -11.81 0.1475 90)
			(layer "B.SilkS")
			(effects
				(font
					(size 0.7 0.7)
					(thickness 0.15)
				)
				(justify right top mirror)
			)
		)
		(property "Value" "C_1u_25V_0402"
			(at -1.022927 -2.155213 90)
			(layer "B.Fab")
			(hide yes)
			(effects
				(font
					(size 0.7 0.7)
					(thickness 0.15)
				)
				(justify right top mirror)
			)
		)
		(property "Datasheet" "https://www.murata.com/products/productdetail?partno=GRM155R61E105KE11%23"
			(at 0 0 90)
			(layer "B.Fab")
			(hide yes)
			(effects
				(font
					(size 1.27 1.27)
					(thickness 0.15)
				)
				(justify mirror)
			)
		)
		(property "Description" "SMD Multilayer Ceramic Capacitor, 1 µF, 25 V, 0402 [1005 Metric], ± 10%, X5R, GRM Series"
			(at 0 0 90)
			(layer "B.Fab")
			(hide yes)
			(effects
				(font
					(size 1.27 1.27)
					(thickness 0.15)
				)
				(justify mirror)
			)
		)
		(property "MPN" "GRM155R61E105KE11J"
			(at 0 0 90)
			(unlocked yes)
			(layer "B.Fab")
			(hide yes)
			(effects
				(font
					(size 1 1)
					(thickness 0.15)
				)
				(justify mirror)
			)
		)
		(property "Manufacturer" "Murata"
			(at 0 0 90)
			(unlocked yes)
			(layer "B.Fab")
			(hide yes)
			(effects
				(font
					(size 1 1)
					(thickness 0.15)
				)
				(justify mirror)
			)
		)
		(property "License" "Apache-2.0"
			(at 0 0 90)
			(unlocked yes)
			(layer "B.Fab")
			(hide yes)
			(effects
				(font
					(size 1 1)
					(thickness 0.15)
				)
				(justify mirror)
			)
		)
		(property "Author" "Antmicro"
			(at 0 0 90)
			(unlocked yes)
			(layer "B.Fab")
			(hide yes)
			(effects
				(font
					(size 1 1)
					(thickness 0.15)
				)
				(justify mirror)
			)
		)
		(property "Val" "1u"
			(at 0 0 90)
			(unlocked yes)
			(layer "B.Fab")
			(hide yes)
			(effects
				(font
					(size 1 1)
					(thickness 0.15)
				)
				(justify mirror)
			)
		)
		(property "Voltage" "25V"
			(at 0 0 90)
			(unlocked yes)
			(layer "B.Fab")
			(hide yes)
			(effects
				(font
					(size 1 1)
					(thickness 0.15)
				)
				(justify mirror)
			)
		)
		(property "Dielectric" "X5R"
			(at 0 0 90)
			(unlocked yes)
			(layer "B.Fab")
			(hide yes)
			(effects
				(font
					(size 1 1)
					(thickness 0.15)
				)
				(justify mirror)
			)
		)
		(sheetname "/X710-AT2 power/")
		(sheetfile "x710-at2-power.kicad_sch")
		(attr smd)
		(fp_rect
			(start -0.925 0.47)
			(end 0.925 -0.47)
			(stroke
				(width 0.05)
				(type default)
			)
			(fill no)
			(layer "B.CrtYd")
		)
		(fp_line
			(start 0.504 -0.248)
			(end -0.494 -0.248)
			(stroke
				(width 0.15)
				(type solid)
			)
			(layer "B.Fab")
		)
		(fp_line
			(start -0.494 -0.248)
			(end -0.494 0.25)
			(stroke
				(width 0.15)
				(type solid)
			)
			(layer "B.Fab")
		)
		(fp_line
			(start 0.504 0.25)
			(end 0.504 -0.248)
			(stroke
				(width 0.15)
				(type solid)
			)
			(layer "B.Fab")
		)
		(fp_line
			(start -0.494 0.25)
			(end 0.504 0.25)
			(stroke
				(width 0.15)
				(type solid)
			)
			(layer "B.Fab")
		)
		(pad "1" smd roundrect
			(at -0.48 0 90)
			(size 0.59 0.64)
			(layers "B.Cu" "B.Mask" "B.Paste")
			(roundrect_rratio 0.25)
			(net 28 "GND")
			(pintype "passive")
		)
		(pad "2" smd roundrect
			(at 0.48 0 90)
			(size 0.59 0.64)
			(layers "B.Cu" "B.Mask" "B.Paste")
			(roundrect_rratio 0.25)
			(net 6 "DVDD")
			(pintype "passive")
		)
	)
	(footprint "antmicro-footprints:R_0402_1005Metric"
		(layer "B.Cu")
		(at 94.48 145.34 90)
		(descr "Resistor SMD 0402")
		(tags "resistor SMD 0402")
		(property "Reference" "R41"
			(at 0.71 -0.38 90)
			(layer "B.SilkS")
			(effects
				(font
					(size 0.7 0.7)
					(thickness 0.15)
				)
				(justify right top mirror)
			)
		)
		(property "Value" "R_220R_0402"
			(at -1.011843 -1.772046 90)
			(layer "B.Fab")
			(hide yes)
			(effects
				(font
					(size 0.7 0.7)
					(thickness 0.15)
				)
				(justify right top mirror)
			)
		)
		(property "Datasheet" "https://www.bourns.com/docs/product-datasheets/cr.pdf"
			(at 0 0 90)
			(layer "B.Fab")
			(hide yes)
			(effects
				(font
					(size 1.27 1.27)
					(thickness 0.15)
				)
				(justify mirror)
			)
		)
		(property "Description" "SMD Chip Resistor, 220 ohm, ± 1%, 62.5 mW, 0402 [1005 Metric], Thick Film, General Purpose"
			(at 0 0 90)
			(layer "B.Fab")
			(hide yes)
			(effects
				(font
					(size 1.27 1.27)
					(thickness 0.15)
				)
				(justify mirror)
			)
		)
		(property "MPN" "CR0402-FX-2200GLF"
			(at 0 0 90)
			(unlocked yes)
			(layer "B.Fab")
			(hide yes)
			(effects
				(font
					(size 1 1)
					(thickness 0.15)
				)
				(justify mirror)
			)
		)
		(property "Manufacturer" "Bourns"
			(at 0 0 90)
			(unlocked yes)
			(layer "B.Fab")
			(hide yes)
			(effects
				(font
					(size 1 1)
					(thickness 0.15)
				)
				(justify mirror)
			)
		)
		(property "License" "Apache-2.0"
			(at 0 0 90)
			(unlocked yes)
			(layer "B.Fab")
			(hide yes)
			(effects
				(font
					(size 1 1)
					(thickness 0.15)
				)
				(justify mirror)
			)
		)
		(property "Author" "Antmicro"
			(at 0 0 90)
			(unlocked yes)
			(layer "B.Fab")
			(hide yes)
			(effects
				(font
					(size 1 1)
					(thickness 0.15)
				)
				(justify mirror)
			)
		)
		(property "Val" "220R"
			(at 0 0 90)
			(unlocked yes)
			(layer "B.Fab")
			(hide yes)
			(effects
				(font
					(size 1 1)
					(thickness 0.15)
				)
				(justify mirror)
			)
		)
		(property "Tolerance" "1%"
			(at 0 0 90)
			(unlocked yes)
			(layer "B.Fab")
			(hide yes)
			(effects
				(font
					(size 1 1)
					(thickness 0.15)
				)
				(justify mirror)
			)
		)
		(sheetname "/2xRJ45/")
		(sheetfile "2xrj45.kicad_sch")
		(attr smd)
		(fp_rect
			(start -0.925 0.47)
			(end 0.925 -0.47)
			(stroke
				(width 0.05)
				(type default)
			)
			(fill no)
			(layer "B.CrtYd")
		)
		(fp_rect
			(start -0.5 0.25)
			(end 0.5 -0.25)
			(stroke
				(width 0.15)
				(type solid)
			)
			(fill no)
			(layer "B.Fab")
		)
		(pad "1" smd roundrect
			(at -0.48 0 90)
			(size 0.59 0.64)
			(layers "B.Cu" "B.Mask" "B.Paste")
			(roundrect_rratio 0.25)
			(net 66 "Net-(J6-LED_GRN-)")
			(pintype "passive")
		)
		(pad "2" smd roundrect
			(at 0.48 0 90)
			(size 0.59 0.64)
			(layers "B.Cu" "B.Mask" "B.Paste")
			(roundrect_rratio 0.25)
			(net 88 "/2xRJ45/~{P1_LED_ACT}")
			(pintype "passive")
		)
	)
	(footprint "antmicro-footprints:TP_SMD_0.75mm"
		(layer "B.Cu")
		(at 103.55 108.7)
		(property "Reference" "TP7"
			(at -0.28 2.5 90)
			(layer "B.SilkS")
			(effects
				(font
					(size 0.7 0.7)
					(thickness 0.15)
				)
				(justify right top mirror)
			)
		)
		(property "Value" "TP_0.75mm_SMD"
			(at 0 -1.2 0)
			(layer "B.Fab")
			(hide yes)
			(effects
				(font
					(size 0.7 0.7)
					(thickness 0.15)
				)
				(justify right top mirror)
			)
		)
		(property "Description" "SMT test point"
			(at 0 0 0)
			(layer "B.Fab")
			(hide yes)
			(effects
				(font
					(size 1.27 1.27)
					(thickness 0.15)
				)
				(justify mirror)
			)
		)
		(property "MPN" ""
			(at 0 0 0)
			(unlocked yes)
			(layer "B.Fab")
			(hide yes)
			(effects
				(font
					(size 1 1)
					(thickness 0.15)
				)
				(justify mirror)
			)
		)
		(property "Manufacturer" ""
			(at 0 0 0)
			(unlocked yes)
			(layer "B.Fab")
			(hide yes)
			(effects
				(font
					(size 1 1)
					(thickness 0.15)
				)
				(justify mirror)
			)
		)
		(property "Author" "Antmicro"
			(at 0 0 0)
			(unlocked yes)
			(layer "B.Fab")
			(hide yes)
			(effects
				(font
					(size 1 1)
					(thickness 0.15)
				)
				(justify mirror)
			)
		)
		(property "License" "Apache-2.0"
			(at 0 0 0)
			(unlocked yes)
			(layer "B.Fab")
			(hide yes)
			(effects
				(font
					(size 1 1)
					(thickness 0.15)
				)
				(justify mirror)
			)
		)
		(sheetname "/X710-AT2 Misc/")
		(sheetfile "x710-at2-mics.kicad_sch")
		(attr exclude_from_pos_files exclude_from_bom)
		(fp_circle
			(center 0 0)
			(end 0.475 0)
			(stroke
				(width 0.05)
				(type default)
			)
			(fill no)
			(layer "B.CrtYd")
		)
		(pad "1" smd circle
			(at 0 0)
			(size 0.75 0.75)
			(layers "B.Cu" "B.Mask")
			(net 362 "/X710-AT2 Misc/NCSI.RXD_0")
			(pinfunction "1")
			(pintype "passive")
		)
	)
	(footprint "antmicro-footprints:R_0402_1005Metric"
		(layer "B.Cu")
		(at 92 111.15 -90)
		(descr "Resistor SMD 0402")
		(tags "resistor SMD 0402")
		(property "Reference" "R70"
			(at -1.13 -1.32 90)
			(layer "B.SilkS")
			(effects
				(font
					(size 0.7 0.7)
					(thickness 0.15)
				)
				(justify left bottom mirror)
			)
		)
		(property "Value" "R_0R_0402"
			(at -1.011843 -1.772046 90)
			(layer "B.Fab")
			(hide yes)
			(effects
				(font
					(size 0.7 0.7)
					(thickness 0.15)
				)
				(justify left bottom mirror)
			)
		)
		(property "Datasheet" "https://industrial.panasonic.com/cdbs/www-data/pdf/RDA0000/AOA0000C301.pdf"
			(at 0 0 90)
			(layer "B.Fab")
			(hide yes)
			(effects
				(font
					(size 1.27 1.27)
					(thickness 0.15)
				)
				(justify mirror)
			)
		)
		(property "Description" "SMD Chip Resistor, Jumper, 0 ohm, 100 mW, 0402 [1005 Metric], Thick Film, General Purpose"
			(at 0 0 90)
			(layer "B.Fab")
			(hide yes)
			(effects
				(font
					(size 1.27 1.27)
					(thickness 0.15)
				)
				(justify mirror)
			)
		)
		(property "MPN" "ERJ2GE0R00X"
			(at 0 0 270)
			(unlocked yes)
			(layer "B.Fab")
			(hide yes)
			(effects
				(font
					(size 1 1)
					(thickness 0.15)
				)
				(justify mirror)
			)
		)
		(property "Manufacturer" "Panasonic"
			(at 0 0 270)
			(unlocked yes)
			(layer "B.Fab")
			(hide yes)
			(effects
				(font
					(size 1 1)
					(thickness 0.15)
				)
				(justify mirror)
			)
		)
		(property "License" "Apache-2.0"
			(at 0 0 270)
			(unlocked yes)
			(layer "B.Fab")
			(hide yes)
			(effects
				(font
					(size 1 1)
					(thickness 0.15)
				)
				(justify mirror)
			)
		)
		(property "Author" "Antmicro"
			(at 0 0 270)
			(unlocked yes)
			(layer "B.Fab")
			(hide yes)
			(effects
				(font
					(size 1 1)
					(thickness 0.15)
				)
				(justify mirror)
			)
		)
		(property "Val" "0R"
			(at 0 0 270)
			(unlocked yes)
			(layer "B.Fab")
			(hide yes)
			(effects
				(font
					(size 1 1)
					(thickness 0.15)
				)
				(justify mirror)
			)
		)
		(property "Tolerance" "~"
			(at 0 0 270)
			(unlocked yes)
			(layer "B.Fab")
			(hide yes)
			(effects
				(font
					(size 1 1)
					(thickness 0.15)
				)
				(justify mirror)
			)
		)
		(property "Current" "1A"
			(at 0 0 270)
			(unlocked yes)
			(layer "B.Fab")
			(hide yes)
			(effects
				(font
					(size 1 1)
					(thickness 0.15)
				)
				(justify mirror)
			)
		)
		(sheetname "/X710-AT2 10GbE/")
		(sheetfile "x710-at2-10gbe.kicad_sch")
		(attr smd)
		(fp_rect
			(start -0.925 0.47)
			(end 0.925 -0.47)
			(stroke
				(width 0.05)
				(type default)
			)
			(fill no)
			(layer "B.CrtYd")
		)
		(fp_rect
			(start -0.5 0.25)
			(end 0.5 -0.25)
			(stroke
				(width 0.15)
				(type solid)
			)
			(fill no)
			(layer "B.Fab")
		)
		(pad "1" smd roundrect
			(at -0.48 0 270)
			(size 0.59 0.64)
			(layers "B.Cu" "B.Mask" "B.Paste")
			(roundrect_rratio 0.25)
			(net 142 "/X710-AT2 10GbE/~{P0_INT}")
			(pintype "passive")
		)
		(pad "2" smd roundrect
			(at 0.48 0 270)
			(size 0.59 0.64)
			(layers "B.Cu" "B.Mask" "B.Paste")
			(roundrect_rratio 0.25)
			(net 198 "/X710-AT2 10GbE/~{P0_INT_R}")
			(pintype "passive")
		)
	)
	(footprint "antmicro-footprints:C_0402_1005Metric"
		(layer "B.Cu")
		(at 97.479998 145.34 -90)
		(descr "Capacitor SMD 0402")
		(tags "capacitor SMD 0402")
		(property "Reference" "C60"
			(at -2.96 -0.480002 90)
			(layer "B.SilkS")
			(effects
				(font
					(size 0.7 0.7)
					(thickness 0.15)
				)
				(justify left bottom mirror)
			)
		)
		(property "Value" "C_470p_0402"
			(at -1.022927 -2.155213 90)
			(layer "B.Fab")
			(hide yes)
			(effects
				(font
					(size 0.7 0.7)
					(thickness 0.15)
				)
				(justify left bottom mirror)
			)
		)
		(property "Datasheet" "https://www.passivecomponent.com/wp-content/uploads/datasheet/WTC_MLCC_General_Purpose.pdf"
			(at 0 0 90)
			(layer "B.Fab")
			(hide yes)
			(effects
				(font
					(size 1.27 1.27)
					(thickness 0.15)
				)
				(justify mirror)
			)
		)
		(property "Description" "SMD Multilayer Ceramic Capacitor, General Purpose, 470 pF, 25 V, 0402 [1005 Metric], ± 10%, X7R"
			(at 0 0 90)
			(layer "B.Fab")
			(hide yes)
			(effects
				(font
					(size 1.27 1.27)
					(thickness 0.15)
				)
				(justify mirror)
			)
		)
		(property "MPN" "0402B471K250CT"
			(at 0 0 270)
			(unlocked yes)
			(layer "B.Fab")
			(hide yes)
			(effects
				(font
					(size 1 1)
					(thickness 0.15)
				)
				(justify mirror)
			)
		)
		(property "Manufacturer" "Walsin"
			(at 0 0 270)
			(unlocked yes)
			(layer "B.Fab")
			(hide yes)
			(effects
				(font
					(size 1 1)
					(thickness 0.15)
				)
				(justify mirror)
			)
		)
		(property "License" "Apache-2.0"
			(at 0 0 270)
			(unlocked yes)
			(layer "B.Fab")
			(hide yes)
			(effects
				(font
					(size 1 1)
					(thickness 0.15)
				)
				(justify mirror)
			)
		)
		(property "Author" "Antmicro"
			(at 0 0 270)
			(unlocked yes)
			(layer "B.Fab")
			(hide yes)
			(effects
				(font
					(size 1 1)
					(thickness 0.15)
				)
				(justify mirror)
			)
		)
		(property "Val" "470p"
			(at 0 0 270)
			(unlocked yes)
			(layer "B.Fab")
			(hide yes)
			(effects
				(font
					(size 1 1)
					(thickness 0.15)
				)
				(justify mirror)
			)
		)
		(property "Voltage" "25V"
			(at 0 0 270)
			(unlocked yes)
			(layer "B.Fab")
			(hide yes)
			(effects
				(font
					(size 1 1)
					(thickness 0.15)
				)
				(justify mirror)
			)
		)
		(property "Dielectric" "X7R"
			(at 0 0 270)
			(unlocked yes)
			(layer "B.Fab")
			(hide yes)
			(effects
				(font
					(size 1 1)
					(thickness 0.15)
				)
				(justify mirror)
			)
		)
		(sheetname "/2xRJ45/")
		(sheetfile "2xrj45.kicad_sch")
		(attr smd)
		(fp_rect
			(start -0.925 0.47)
			(end 0.925 -0.47)
			(stroke
				(width 0.05)
				(type default)
			)
			(fill no)
			(layer "B.CrtYd")
		)
		(fp_line
			(start -0.494 0.25)
			(end 0.504 0.25)
			(stroke
				(width 0.15)
				(type solid)
			)
			(layer "B.Fab")
		)
		(fp_line
			(start 0.504 0.25)
			(end 0.504 -0.248)
			(stroke
				(width 0.15)
				(type solid)
			)
			(layer "B.Fab")
		)
		(fp_line
			(start -0.494 -0.248)
			(end -0.494 0.25)
			(stroke
				(width 0.15)
				(type solid)
			)
			(layer "B.Fab")
		)
		(fp_line
			(start 0.504 -0.248)
			(end -0.494 -0.248)
			(stroke
				(width 0.15)
				(type solid)
			)
			(layer "B.Fab")
		)
		(pad "1" smd roundrect
			(at -0.48 0 270)
			(size 0.59 0.64)
			(layers "B.Cu" "B.Mask" "B.Paste")
			(roundrect_rratio 0.25)
			(net 28 "GND")
			(pintype "passive")
		)
		(pad "2" smd roundrect
			(at 0.48 0 270)
			(size 0.59 0.64)
			(layers "B.Cu" "B.Mask" "B.Paste")
			(roundrect_rratio 0.25)
			(net 61 "Net-(J6-LED_YG_Y-)")
			(pintype "passive")
		)
	)
	(footprint "antmicro-footprints:TP_SMD_0.75mm"
		(layer "B.Cu")
		(at 103.55 107.2 90)
		(property "Reference" "TP6"
			(at 0.45 0.54 180)
			(layer "B.SilkS")
			(effects
				(font
					(size 0.7 0.7)
					(thickness 0.15)
				)
				(justify right top mirror)
			)
		)
		(property "Value" "TP_0.75mm_SMD"
			(at 0 -1.2 90)
			(layer "B.Fab")
			(hide yes)
			(effects
				(font
					(size 0.7 0.7)
					(thickness 0.15)
				)
				(justify right top mirror)
			)
		)
		(property "Description" "SMT test point"
			(at 0 0 90)
			(layer "B.Fab")
			(hide yes)
			(effects
				(font
					(size 1.27 1.27)
					(thickness 0.15)
				)
				(justify mirror)
			)
		)
		(property "MPN" ""
			(at 0 0 90)
			(unlocked yes)
			(layer "B.Fab")
			(hide yes)
			(effects
				(font
					(size 1 1)
					(thickness 0.15)
				)
				(justify mirror)
			)
		)
		(property "Manufacturer" ""
			(at 0 0 90)
			(unlocked yes)
			(layer "B.Fab")
			(hide yes)
			(effects
				(font
					(size 1 1)
					(thickness 0.15)
				)
				(justify mirror)
			)
		)
		(property "Author" "Antmicro"
			(at 0 0 90)
			(unlocked yes)
			(layer "B.Fab")
			(hide yes)
			(effects
				(font
					(size 1 1)
					(thickness 0.15)
				)
				(justify mirror)
			)
		)
		(property "License" "Apache-2.0"
			(at 0 0 90)
			(unlocked yes)
			(layer "B.Fab")
			(hide yes)
			(effects
				(font
					(size 1 1)
					(thickness 0.15)
				)
				(justify mirror)
			)
		)
		(sheetname "/X710-AT2 Misc/")
		(sheetfile "x710-at2-mics.kicad_sch")
		(attr exclude_from_pos_files exclude_from_bom)
		(fp_circle
			(center 0 0)
			(end 0.475 0)
			(stroke
				(width 0.05)
				(type default)
			)
			(fill no)
			(layer "B.CrtYd")
		)
		(pad "1" smd circle
			(at 0 0 90)
			(size 0.75 0.75)
			(layers "B.Cu" "B.Mask")
			(net 363 "/X710-AT2 Misc/NCSI.TXD_0")
			(pinfunction "1")
			(pintype "passive")
		)
	)
)
